(kicad_pcb
	(version 20260206)
	(generator "pcbnew")
	(generator_version "10.0")
	(general
		(thickness 1.6)
		(legacy_teardrops no)
	)
	(paper "A4")
	(title_block
		(title "Wiwynn_Tioga_Pass_MB.brd")
		(comment 1 "Tioga Pass / footprints 1642-1647 of 4770")
	)
	(layers
		(0 "F.Cu" signal "TOP")
		(4 "In1.Cu" signal "L2GND")
		(6 "In2.Cu" signal "L3")
		(8 "In3.Cu" signal "L4GND")
		(10 "In4.Cu" signal "L5")
		(12 "In5.Cu" signal "L6GND")
		(14 "In6.Cu" signal "L7VCC")
		(16 "In7.Cu" signal "L8VCC")
		(18 "In8.Cu" signal "L9GND")
		(20 "In9.Cu" signal "L10")
		(22 "In10.Cu" signal "L11GND")
		(24 "In11.Cu" signal "L12")
		(26 "In12.Cu" signal "L13GND")
		(2 "B.Cu" signal "BOTTOM")
		(9 "F.Adhes" user "F.Adhesive")
		(11 "B.Adhes" user "B.Adhesive")
		(13 "F.Paste" user "Package Geometry/Pastemask Top")
		(15 "B.Paste" user "Package Geometry/Pastemask Bottom")
		(5 "F.SilkS" user "Ref Des/Silkscreen Top")
		(7 "B.SilkS" user "Ref Des/Silkscreen Bottom")
		(1 "F.Mask" user "Board Geometry/Soldermask Top")
		(3 "B.Mask" user "Board Geometry/Soldermask Bottom")
		(17 "Dwgs.User" user "User.Drawings")
		(19 "Cmts.User" user "User.Comments")
		(21 "Eco1.User" user "User.Eco1")
		(23 "Eco2.User" user "User.Eco2")
		(25 "Edge.Cuts" user "Board Geometry/Outline")
		(27 "Margin" user)
		(31 "F.CrtYd" user "Package Geometry/Place Bound Top")
		(29 "B.CrtYd" user "Package Geometry/Place Bound Bottom")
		(35 "F.Fab" user "Ref Des/Assembly Top")
		(33 "B.Fab" user "Ref Des/Assembly Bottom")
	)
	(footprint ""
		(layer "F.Cu")
		(at 492.315246 -20.549108 90)
		(property "Reference" "Q7E7"
			(at 4.16433 -1.143 0)
			(unlocked yes)
			(layer "F.SilkS")
			(effects
				(font
					(size 0.7874 0.5842)
					(thickness 0.1524)
				)
				(justify left)
			)
		)
		(property "Value" ""
			(at 0 0 90)
			(layer "F.Fab")
			(effects
				(font
					(size 1.27 1.27)
				)
			)
		)
		(duplicate_pad_numbers_are_jumpers no)
		(fp_line
			(start -0.245364 -1.379982)
			(end 3.15468 -1.379982)
			(stroke
				(width 0.1524)
				(type default)
			)
			(layer "F.SilkS")
		)
		(fp_line
			(start -0.245364 2.020062)
			(end 3.15468 2.020062)
			(stroke
				(width 0.1524)
				(type default)
			)
			(layer "F.SilkS")
		)
		(fp_circle
			(center -0.94996 -1.512316)
			(end -0.94996 -1.385316)
			(stroke
				(width 0.254)
				(type default)
			)
			(fill no)
			(layer "F.SilkS")
		)
		(fp_poly
			(pts
				(xy 0.890016 -0.82296) (xy 0.890016 1.46304) (xy 3.404616 1.46304) (xy 3.404616 1.13284) (xy 2.617216 1.13284)
				(xy 2.617216 0.811022) (xy 3.404616 0.811022) (xy 3.404616 0.480822) (xy 2.617216 0.480822) (xy 2.617216 0.159258)
				(xy 3.404616 0.159258) (xy 3.404616 -0.170942) (xy 2.617216 -0.170942) (xy 2.617216 -0.49276) (xy 3.404616 -0.49276)
				(xy 3.404616 -0.82296)
			)
			(stroke
				(width 0)
				(type default)
			)
			(fill yes)
			(layer "F.Paste")
		)
		(fp_poly
			(pts
				(xy -0.245364 -1.379982) (xy -0.245364 2.020062) (xy 3.15468 2.020062) (xy 3.15468 -1.379982)
			)
			(stroke
				(width 0)
				(type default)
			)
			(fill no)
			(layer "F.CrtYd")
		)
		(fp_line
			(start 3.15468 -1.379982)
			(end 3.15468 2.020062)
			(stroke
				(width 0.1)
				(type default)
			)
			(layer "F.Fab")
		)
		(fp_line
			(start -0.245364 -1.379982)
			(end 3.15468 -1.379982)
			(stroke
				(width 0.1)
				(type default)
			)
			(layer "F.Fab")
		)
		(fp_line
			(start 3.15468 2.020062)
			(end -0.245364 2.020062)
			(stroke
				(width 0.1)
				(type default)
			)
			(layer "F.Fab")
		)
		(fp_line
			(start -0.245364 2.020062)
			(end -0.245364 -1.379982)
			(stroke
				(width 0.1)
				(type default)
			)
			(layer "F.Fab")
		)
		(fp_circle
			(center -0.94996 -1.512316)
			(end -0.94996 -1.385316)
			(stroke
				(width 0.254)
				(type default)
			)
			(fill no)
			(layer "F.Fab")
		)
		(pad "1" smd custom
			(at 0 0 90)
			(size 0.24765 0.24765)
			(layers "F.Cu" "F.Mask" "F.Paste")
			(net "P12V")
			(options
				(clearance outline)
				(anchor circle)
			)
			(primitives
				(gr_poly
					(pts
						(xy 0.4953 0.8255) (xy 0.4953 -0.8255) (xy -0.4953 -0.8255) (xy -0.4953 -0.4953) (xy 0.0127 -0.4953)
						(xy 0.0127 -0.1651) (xy -0.4953 -0.1651) (xy -0.4953 0.1651) (xy 0.0127 0.1651) (xy 0.0127 0.4953)
						(xy -0.4953 0.4953) (xy -0.4953 0.8255)
					)
					(width 0)
					(fill yes)
				)
			)
		)
		(pad "4" smd rect
			(at 0 1.30048 90)
			(size 0.9906 0.3302)
			(layers "F.Cu" "F.Mask" "F.Paste")
			(net "P12V_SWITCH_G")
		)
		(pad "5" smd custom
			(at 2.147316 0.32004 90)
			(size 0.5715 0.5715)
			(layers "F.Cu" "F.Mask" "F.Paste")
			(net "P12V_STBY")
			(options
				(clearance outline)
				(anchor circle)
			)
			(primitives
				(gr_poly
					(pts
						(xy -1.2573 -1.143) (xy -1.2573 1.143) (xy 1.2573 1.143) (xy 1.2573 0.8128) (xy 0.4699 0.8128)
						(xy 0.4699 0.490982) (xy 1.2573 0.490982) (xy 1.2573 0.160782) (xy 0.4699 0.160782) (xy 0.4699 -0.160782)
						(xy 1.2573 -0.160782) (xy 1.2573 -0.490982) (xy 0.4699 -0.490982) (xy 0.4699 -0.8128) (xy 1.2573 -0.8128)
						(xy 1.2573 -1.143)
					)
					(width 0)
					(fill yes)
				)
			)
		)
	)
	(footprint ""
		(layer "F.Cu")
		(at 407.8351 -63.373 -90)
		(property "Reference" "R8E6"
			(at 0 0 270)
			(layer "F.SilkS")
			(hide yes)
			(effects
				(font
					(size 1.27 1.27)
				)
			)
		)
		(property "Value" ""
			(at 0 0 270)
			(layer "F.Fab")
			(effects
				(font
					(size 1.27 1.27)
				)
			)
		)
		(duplicate_pad_numbers_are_jumpers no)
		(fp_poly
			(pts
				(xy -0.2794 -0.1016) (xy 0.2794 -0.1016) (xy 0.2794 0.9906) (xy -0.2794 0.9906)
			)
			(stroke
				(width 0)
				(type default)
			)
			(fill no)
			(layer "F.CrtYd")
		)
		(pad "1" smd rect
			(at 0 0 270)
			(size 0.508 0.508)
			(layers "F.Cu" "F.Mask" "F.Paste")
			(net "P3V3_STBY")
		)
		(pad "2" smd rect
			(at 0 0.889 270)
			(size 0.508 0.508)
			(layers "F.Cu" "F.Mask" "F.Paste")
			(net "SPI_PCH_MOSI")
		)
		(zone
			(layer "F.Cu")
			(hatch none 0.5)
			(connect_pads
				(clearance 0)
			)
			(min_thickness 0.25)
			(keepout
				(tracks not_allowed)
				(vias allowed)
				(pads allowed)
				(copperpour not_allowed)
				(footprints allowed)
			)
			(placement
				(enabled no)
				(sheetname "")
			)
			(fill
				(thermal_gap 0.5)
				(thermal_bridge_width 0.5)
				(island_removal_mode 0)
			)
			(polygon
				(pts
					(xy 407.2001 -63.627) (xy 407.2001 -63.119) (xy 407.5811 -63.119) (xy 407.5811 -63.627)
				)
			)
		)
		(zone
			(layer "F.Cu")
			(hatch none 0.5)
			(connect_pads
				(clearance 0)
			)
			(min_thickness 0.25)
			(keepout
				(tracks allowed)
				(vias not_allowed)
				(pads allowed)
				(copperpour not_allowed)
				(footprints allowed)
			)
			(placement
				(enabled no)
				(sheetname "")
			)
			(fill
				(thermal_gap 0.5)
				(thermal_bridge_width 0.5)
				(island_removal_mode 0)
			)
			(polygon
				(pts
					(xy 407.5811 -63.627) (xy 407.5811 -63.119) (xy 407.2001 -63.119) (xy 407.2001 -63.627)
				)
			)
		)
	)
	(footprint ""
		(layer "F.Cu")
		(at 3.2004 -5.675376 -90)
		(property "Reference" "C1G6"
			(at 0 0 270)
			(layer "F.SilkS")
			(hide yes)
			(effects
				(font
					(size 1.27 1.27)
				)
			)
		)
		(property "Value" ""
			(at 0 0 270)
			(layer "F.Fab")
			(effects
				(font
					(size 1.27 1.27)
				)
			)
		)
		(duplicate_pad_numbers_are_jumpers no)
		(fp_poly
			(pts
				(xy 0.3048 -0.1016) (xy 0.3048 0.9906) (xy -0.3048 0.9906) (xy -0.3048 -0.1016)
			)
			(stroke
				(width 0)
				(type default)
			)
			(fill no)
			(layer "F.CrtYd")
		)
		(fp_line
			(start -0.3048 0.9906)
			(end 0.3048 0.9906)
			(stroke
				(width 0.1)
				(type default)
			)
			(layer "F.Fab")
		)
		(fp_line
			(start 0.3048 0.9906)
			(end 0.3048 -0.1016)
			(stroke
				(width 0.1)
				(type default)
			)
			(layer "F.Fab")
		)
		(fp_line
			(start -0.3048 -0.1016)
			(end -0.3048 0.9906)
			(stroke
				(width 0.1)
				(type default)
			)
			(layer "F.Fab")
		)
		(fp_line
			(start 0.3048 -0.1016)
			(end -0.3048 -0.1016)
			(stroke
				(width 0.1)
				(type default)
			)
			(layer "F.Fab")
		)
		(pad "1" smd rect
			(at 0 0 270)
			(size 0.508 0.508)
			(layers "F.Cu" "F.Mask" "F.Paste")
			(net "VR_PVDDQ_GHJ_PH1_VCIN")
		)
		(pad "2" smd rect
			(at 0 0.889 270)
			(size 0.508 0.508)
			(layers "F.Cu" "F.Mask" "F.Paste")
			(net "GND")
		)
		(zone
			(layer "F.Cu")
			(hatch none 0.5)
			(connect_pads
				(clearance 0)
			)
			(min_thickness 0.25)
			(keepout
				(tracks not_allowed)
				(vias allowed)
				(pads allowed)
				(copperpour not_allowed)
				(footprints allowed)
			)
			(placement
				(enabled no)
				(sheetname "")
			)
			(fill
				(thermal_gap 0.5)
				(thermal_bridge_width 0.5)
				(island_removal_mode 0)
			)
			(polygon
				(pts
					(xy 2.5654 -5.929376) (xy 2.5654 -5.421376) (xy 2.9464 -5.421376) (xy 2.9464 -5.929376)
				)
			)
		)
		(zone
			(layer "F.Cu")
			(hatch none 0.5)
			(connect_pads
				(clearance 0)
			)
			(min_thickness 0.25)
			(keepout
				(tracks allowed)
				(vias not_allowed)
				(pads allowed)
				(copperpour not_allowed)
				(footprints allowed)
			)
			(placement
				(enabled no)
				(sheetname "")
			)
			(fill
				(thermal_gap 0.5)
				(thermal_bridge_width 0.5)
				(island_removal_mode 0)
			)
			(polygon
				(pts
					(xy 2.9464 -5.929376) (xy 2.9464 -5.421376) (xy 2.5654 -5.421376) (xy 2.5654 -5.929376)
				)
			)
		)
	)
	(footprint ""
		(layer "F.Cu")
		(at 498.620034 -138.678666 90)
		(property "Reference" "DS9A4"
			(at -0.60071 0.94742 0)
			(unlocked yes)
			(layer "F.SilkS")
			(effects
				(font
					(size 0.7874 0.5842)
					(thickness 0.1524)
				)
			)
		)
		(property "Value" ""
			(at 0 0 90)
			(layer "F.Fab")
			(effects
				(font
					(size 1.27 1.27)
				)
			)
		)
		(duplicate_pad_numbers_are_jumpers no)
		(fp_line
			(start 0.992632 -1.34874)
			(end 0.992632 -0.437134)
			(stroke
				(width 0.1524)
				(type default)
			)
			(layer "F.SilkS")
		)
		(fp_line
			(start 1.473454 -0.437134)
			(end 0.992632 0.395732)
			(stroke
				(width 0.1524)
				(type default)
			)
			(layer "F.SilkS")
		)
		(fp_line
			(start 0.992632 -0.437134)
			(end 1.473454 -0.437134)
			(stroke
				(width 0.1524)
				(type default)
			)
			(layer "F.SilkS")
		)
		(fp_line
			(start 0.51181 -0.437134)
			(end 0.992632 -0.437134)
			(stroke
				(width 0.1524)
				(type default)
			)
			(layer "F.SilkS")
		)
		(fp_line
			(start 0.992632 0.395732)
			(end 0.51181 -0.437134)
			(stroke
				(width 0.1524)
				(type default)
			)
			(layer "F.SilkS")
		)
		(fp_line
			(start 0.51181 0.395732)
			(end 1.473454 0.395732)
			(stroke
				(width 0.1524)
				(type default)
			)
			(layer "F.SilkS")
		)
		(fp_line
			(start 0.992632 1.519174)
			(end 0.992632 0.395732)
			(stroke
				(width 0.1524)
				(type default)
			)
			(layer "F.SilkS")
		)
		(fp_rect
			(start -0.4064 1.6891)
			(end 0.4064 0.0889)
			(stroke
				(width 0)
				(type default)
			)
			(fill no)
			(layer "F.CrtYd")
		)
		(fp_line
			(start 1.473454 -0.437134)
			(end 0.992632 0.395732)
			(stroke
				(width 0.1)
				(type default)
			)
			(layer "F.Fab")
		)
		(fp_line
			(start 0.992632 -0.437134)
			(end 0.992632 -1.34874)
			(stroke
				(width 0.1)
				(type default)
			)
			(layer "F.Fab")
		)
		(fp_line
			(start 0.51181 -0.437134)
			(end 1.473454 -0.437134)
			(stroke
				(width 0.1)
				(type default)
			)
			(layer "F.Fab")
		)
		(fp_line
			(start 0.4064 0.0889)
			(end 0.4064 1.6891)
			(stroke
				(width 0.1)
				(type default)
			)
			(layer "F.Fab")
		)
		(fp_line
			(start -0.4064 0.0889)
			(end 0.4064 0.0889)
			(stroke
				(width 0.1)
				(type default)
			)
			(layer "F.Fab")
		)
		(fp_line
			(start 0.992632 0.395732)
			(end 0.51181 -0.437134)
			(stroke
				(width 0.1)
				(type default)
			)
			(layer "F.Fab")
		)
		(fp_line
			(start 0.992632 0.395732)
			(end 0.992632 1.519174)
			(stroke
				(width 0.1)
				(type default)
			)
			(layer "F.Fab")
		)
		(fp_line
			(start 0.51181 0.395732)
			(end 1.473454 0.395732)
			(stroke
				(width 0.1)
				(type default)
			)
			(layer "F.Fab")
		)
		(fp_line
			(start 0.4064 1.6891)
			(end -0.4064 1.6891)
			(stroke
				(width 0.1)
				(type default)
			)
			(layer "F.Fab")
		)
		(fp_line
			(start -0.4064 1.6891)
			(end -0.4064 0.0889)
			(stroke
				(width 0.1)
				(type default)
			)
			(layer "F.Fab")
		)
		(pad "1" smd rect
			(at 0 0 90)
			(size 0.762 1.27)
			(layers "F.Cu" "F.Mask" "F.Paste")
			(net "FM_UARTSW_LSB_R_N")
		)
		(pad "2" smd rect
			(at 0 1.778 90)
			(size 0.762 1.27)
			(layers "F.Cu" "F.Mask" "F.Paste")
			(net "FM_UARTSW_LSB_N")
		)
		(zone
			(layer "F.Cu")
			(hatch none 0.5)
			(connect_pads
				(clearance 0)
			)
			(min_thickness 0.25)
			(keepout
				(tracks not_allowed)
				(vias allowed)
				(pads allowed)
				(copperpour not_allowed)
				(footprints allowed)
			)
			(placement
				(enabled no)
				(sheetname "")
			)
			(fill
				(thermal_gap 0.5)
				(thermal_bridge_width 0.5)
				(island_removal_mode 0)
			)
			(polygon
				(pts
					(xy 499.280434 -138.297666) (xy 499.280434 -139.059666) (xy 499.737634 -139.059666) (xy 499.737634 -138.297666)
				)
			)
		)
		(zone
			(layer "F.Cu")
			(hatch none 0.5)
			(connect_pads
				(clearance 0)
			)
			(min_thickness 0.25)
			(keepout
				(tracks allowed)
				(vias not_allowed)
				(pads allowed)
				(copperpour not_allowed)
				(footprints allowed)
			)
			(placement
				(enabled no)
				(sheetname "")
			)
			(fill
				(thermal_gap 0.5)
				(thermal_bridge_width 0.5)
				(island_removal_mode 0)
			)
			(polygon
				(pts
					(xy 499.737634 -138.297666) (xy 499.737634 -139.059666) (xy 499.280434 -139.059666) (xy 499.280434 -138.297666)
				)
			)
		)
	)
	(footprint ""
		(layer "F.Cu")
		(at 92.911168 -149.8092 -90)
		(property "Reference" "C2A5"
			(at 0 0 270)
			(layer "F.SilkS")
			(hide yes)
			(effects
				(font
					(size 1.27 1.27)
				)
			)
		)
		(property "Value" ""
			(at 0 0 270)
			(layer "F.Fab")
			(effects
				(font
					(size 1.27 1.27)
				)
			)
		)
		(duplicate_pad_numbers_are_jumpers no)
		(fp_rect
			(start -0.500126 1.598422)
			(end 0.500126 -0.201422)
			(stroke
				(width 0)
				(type default)
			)
			(fill no)
			(layer "F.CrtYd")
		)
		(fp_line
			(start -0.500126 1.598422)
			(end -0.500126 -0.201422)
			(stroke
				(width 0.1)
				(type default)
			)
			(layer "F.Fab")
		)
		(fp_line
			(start 0.500126 1.598422)
			(end -0.500126 1.598422)
			(stroke
				(width 0.1)
				(type default)
			)
			(layer "F.Fab")
		)
		(fp_line
			(start -0.500126 -0.201422)
			(end 0.500126 -0.201422)
			(stroke
				(width 0.1)
				(type default)
			)
			(layer "F.Fab")
		)
		(fp_line
			(start 0.500126 -0.201422)
			(end 0.500126 1.598422)
			(stroke
				(width 0.1)
				(type default)
			)
			(layer "F.Fab")
		)
		(pad "1" smd rect
			(at 0 0 180)
			(size 0.889 0.9906)
			(layers "F.Cu" "F.Mask" "F.Paste")
			(net "PVDDQ_KLM")
		)
		(pad "2" smd rect
			(at 0 1.397 180)
			(size 0.889 0.9906)
			(layers "F.Cu" "F.Mask" "F.Paste")
			(net "GND")
		)
		(zone
			(layer "F.Cu")
			(hatch none 0.5)
			(connect_pads
				(clearance 0)
			)
			(min_thickness 0.25)
			(keepout
				(tracks allowed)
				(vias not_allowed)
				(pads allowed)
				(copperpour not_allowed)
				(footprints allowed)
			)
			(placement
				(enabled no)
				(sheetname "")
			)
			(fill
				(thermal_gap 0.5)
				(thermal_bridge_width 0.5)
				(island_removal_mode 0)
			)
			(polygon
				(pts
					(xy 91.958668 -150.3045) (xy 91.958668 -149.3139) (xy 92.466668 -149.3139) (xy 92.466668 -150.3045)
				)
			)
		)
		(zone
			(layer "F.Cu")
			(hatch none 0.5)
			(connect_pads
				(clearance 0)
			)
			(min_thickness 0.25)
			(keepout
				(tracks not_allowed)
				(vias allowed)
				(pads allowed)
				(copperpour not_allowed)
				(footprints allowed)
			)
			(placement
				(enabled no)
				(sheetname "")
			)
			(fill
				(thermal_gap 0.5)
				(thermal_bridge_width 0.5)
				(island_removal_mode 0)
			)
			(polygon
				(pts
					(xy 91.958668 -150.3045) (xy 91.958668 -149.3139) (xy 92.466668 -149.3139) (xy 92.466668 -150.3045)
				)
			)
		)
	)
	(footprint ""
		(layer "F.Cu")
		(at 194.7418 -84.3026 -90)
		(property "Reference" "C4D10"
			(at 0 0 270)
			(layer "F.SilkS")
			(hide yes)
			(effects
				(font
					(size 1.27 1.27)
				)
			)
		)
		(property "Value" ""
			(at 0 0 270)
			(layer "F.Fab")
			(effects
				(font
					(size 1.27 1.27)
				)
			)
		)
		(duplicate_pad_numbers_are_jumpers no)
		(fp_poly
			(pts
				(xy 0.3048 -0.1016) (xy 0.3048 0.9906) (xy -0.3048 0.9906) (xy -0.3048 -0.1016)
			)
			(stroke
				(width 0)
				(type default)
			)
			(fill no)
			(layer "F.CrtYd")
		)
		(fp_line
			(start -0.3048 0.9906)
			(end 0.3048 0.9906)
			(stroke
				(width 0.1)
				(type default)
			)
			(layer "F.Fab")
		)
		(fp_line
			(start 0.3048 0.9906)
			(end 0.3048 -0.1016)
			(stroke
				(width 0.1)
				(type default)
			)
			(layer "F.Fab")
		)
		(fp_line
			(start -0.3048 -0.1016)
			(end -0.3048 0.9906)
			(stroke
				(width 0.1)
				(type default)
			)
			(layer "F.Fab")
		)
		(fp_line
			(start 0.3048 -0.1016)
			(end -0.3048 -0.1016)
			(stroke
				(width 0.1)
				(type default)
			)
			(layer "F.Fab")
		)
		(pad "1" smd rect
			(at 0 0 270)
			(size 0.508 0.508)
			(layers "F.Cu" "F.Mask" "F.Paste")
			(net "VR_FET_SW_P12V_STBY_PVCCIN_CPU0")
		)
		(pad "2" smd rect
			(at 0 0.889 270)
			(size 0.508 0.508)
			(layers "F.Cu" "F.Mask" "F.Paste")
			(net "GND")
		)
		(zone
			(layer "F.Cu")
			(hatch none 0.5)
			(connect_pads
				(clearance 0)
			)
			(min_thickness 0.25)
			(keepout
				(tracks not_allowed)
				(vias allowed)
				(pads allowed)
				(copperpour not_allowed)
				(footprints allowed)
			)
			(placement
				(enabled no)
				(sheetname "")
			)
			(fill
				(thermal_gap 0.5)
				(thermal_bridge_width 0.5)
				(island_removal_mode 0)
			)
			(polygon
				(pts
					(xy 194.1068 -84.5566) (xy 194.1068 -84.0486) (xy 194.4878 -84.0486) (xy 194.4878 -84.5566)
				)
			)
		)
		(zone
			(layer "F.Cu")
			(hatch none 0.5)
			(connect_pads
				(clearance 0)
			)
			(min_thickness 0.25)
			(keepout
				(tracks allowed)
				(vias not_allowed)
				(pads allowed)
				(copperpour not_allowed)
				(footprints allowed)
			)
			(placement
				(enabled no)
				(sheetname "")
			)
			(fill
				(thermal_gap 0.5)
				(thermal_bridge_width 0.5)
				(island_removal_mode 0)
			)
			(polygon
				(pts
					(xy 194.4878 -84.5566) (xy 194.4878 -84.0486) (xy 194.1068 -84.0486) (xy 194.1068 -84.5566)
				)
			)
		)
	)
)
